# T6G (Grand Teton) — schematic netlist excerpt (pin names and nets, part order shuffled) for the footprints in the layout excerpt that follows; sources: Cadence DE-HDL packaged netlist, KiCad conversion of 04192023_DAF0TMB3IC0_F0TG_MB_C_brd_V02_OCP.brd

C2588  Q_CAP  22UF 4V 20% X6S  pkg C0402  page 70 : A = PVDDCR_SOC_P0 ; B = GND
R2926  Q_RES  4.7K 5% CHIP  pkg 0402LF  page 130 : A = BMC_MONITER_BUF_R ; B = GND

(kicad_pcb
	(version 20260206)
	(generator "pcbnew")
	(generator_version "10.0")
	(general
		(thickness 1.6)
		(legacy_teardrops no)
	)
	(paper "A4")
	(title_block
		(title "04192023_DAF0TMB3IC0_F0TG_MB_C_brd_V02_OCP.brd")
		(comment 1 "Grand Teton / footprints 5082-5083 of 8354")
	)
	(layers
		(0 "F.Cu" signal "TOP")
		(4 "In1.Cu" signal "GND")
		(6 "In2.Cu" signal "IN1")
		(8 "In3.Cu" signal "GND1")
		(10 "In4.Cu" signal "IN2")
		(12 "In5.Cu" signal "GND2")
		(14 "In6.Cu" signal "IN3")
		(16 "In7.Cu" signal "GND3")
		(18 "In8.Cu" signal "VCC")
		(20 "In9.Cu" signal "VCC1")
		(22 "In10.Cu" signal "GND4")
		(24 "In11.Cu" signal "IN4")
		(26 "In12.Cu" signal "GND5")
		(28 "In13.Cu" signal "IN5")
		(30 "In14.Cu" signal "GND6")
		(32 "In15.Cu" signal "IN6")
		(34 "In16.Cu" signal "GND7")
		(2 "B.Cu" signal "BOTTOM")
		(9 "F.Adhes" user "F.Adhesive")
		(11 "B.Adhes" user "B.Adhesive")
		(13 "F.Paste" user "Package Geometry/Pastemask Top")
		(15 "B.Paste" user "Package Geometry/Pastemask Bottom")
		(5 "F.SilkS" user "Ref Des/Silkscreen Top")
		(7 "B.SilkS" user "Ref Des/Silkscreen Bottom")
		(1 "F.Mask" user "Board Geometry/Soldermask Top")
		(3 "B.Mask" user "Board Geometry/Soldermask Bottom")
		(17 "Dwgs.User" user "User.Drawings")
		(19 "Cmts.User" user "User.Comments")
		(21 "Eco1.User" user "User.Eco1")
		(23 "Eco2.User" user "User.Eco2")
		(25 "Edge.Cuts" user "Board Geometry/Outline")
		(27 "Margin" user)
		(31 "F.CrtYd" user "Package Geometry/Place Bound Top")
		(29 "B.CrtYd" user "Package Geometry/Place Bound Bottom")
		(35 "F.Fab" user "Ref Des/Assembly Top")
		(33 "B.Fab" user "Ref Des/Assembly Bottom")
	)
	(footprint ""
		(layer "B.Cu")
		(at 180.166518 -412.949644 -90)
		(property "Reference" "R2926"
			(at 0 0 90)
			(layer "B.SilkS")
			(hide yes)
			(effects
				(font
					(size 1.27 1.27)
				)
				(justify mirror)
			)
		)
		(property "Value" ""
			(at 0 0 90)
			(layer "B.Fab")
			(effects
				(font
					(size 1.27 1.27)
				)
				(justify mirror)
			)
		)
		(duplicate_pad_numbers_are_jumpers no)
		(fp_line
			(start -0.7874 0.4064)
			(end 0.7874 0.4064)
			(stroke
				(width 0.1524)
				(type default)
			)
			(layer "B.SilkS")
		)
		(fp_line
			(start 0.7874 0.4064)
			(end 0.7874 -0.4064)
			(stroke
				(width 0.1524)
				(type default)
			)
			(layer "B.SilkS")
		)
		(fp_line
			(start -0.7874 -0.4064)
			(end -0.7874 0.4064)
			(stroke
				(width 0.1524)
				(type default)
			)
			(layer "B.SilkS")
		)
		(fp_line
			(start 0.7874 -0.4064)
			(end -0.7874 -0.4064)
			(stroke
				(width 0.1524)
				(type default)
			)
			(layer "B.SilkS")
		)
		(fp_line
			(start -0.67945 0.3048)
			(end -0.120396 0.3048)
			(stroke
				(width 0.1)
				(type default)
			)
			(layer "B.Fab")
		)
		(fp_line
			(start -0.120396 0.3048)
			(end -0.120396 0.2794)
			(stroke
				(width 0.1)
				(type default)
			)
			(layer "B.Fab")
		)
		(fp_line
			(start 0.12065 0.3048)
			(end 0.67945 0.3048)
			(stroke
				(width 0.1)
				(type default)
			)
			(layer "B.Fab")
		)
		(fp_line
			(start 0.67945 0.3048)
			(end 0.67945 -0.305054)
			(stroke
				(width 0.1)
				(type default)
			)
			(layer "B.Fab")
		)
		(fp_line
			(start -0.120396 0.2794)
			(end 0.12065 0.2794)
			(stroke
				(width 0.1)
				(type default)
			)
			(layer "B.Fab")
		)
		(fp_line
			(start 0.12065 0.2794)
			(end 0.12065 0.3048)
			(stroke
				(width 0.1)
				(type default)
			)
			(layer "B.Fab")
		)
		(fp_line
			(start -0.12065 -0.2794)
			(end -0.12065 -0.3048)
			(stroke
				(width 0.1)
				(type default)
			)
			(layer "B.Fab")
		)
		(fp_line
			(start 0.12065 -0.2794)
			(end -0.12065 -0.2794)
			(stroke
				(width 0.1)
				(type default)
			)
			(layer "B.Fab")
		)
		(fp_line
			(start -0.67945 -0.3048)
			(end -0.67945 0.3048)
			(stroke
				(width 0.1)
				(type default)
			)
			(layer "B.Fab")
		)
		(fp_line
			(start -0.12065 -0.3048)
			(end -0.67945 -0.3048)
			(stroke
				(width 0.1)
				(type default)
			)
			(layer "B.Fab")
		)
		(fp_line
			(start 0.12065 -0.305054)
			(end 0.12065 -0.2794)
			(stroke
				(width 0.1)
				(type default)
			)
			(layer "B.Fab")
		)
		(fp_line
			(start 0.67945 -0.305054)
			(end 0.12065 -0.305054)
			(stroke
				(width 0.1)
				(type default)
			)
			(layer "B.Fab")
		)
		(pad "1" smd circle
			(at 0.40005 0 90)
			(size 0 0)
			(layers "B.Cu" "B.Mask" "B.Paste")
			(net "BMC_MONITER_BUF_R")
		)
		(pad "2" smd circle
			(at -0.40005 0 90)
			(size 0 0)
			(layers "B.Cu" "B.Mask" "B.Paste")
			(net "GND")
		)
	)
	(footprint ""
		(layer "B.Cu")
		(at 352.247454 -251.78131)
		(property "Reference" "C2588"
			(at 0 0 0)
			(layer "B.SilkS")
			(hide yes)
			(effects
				(font
					(size 1.27 1.27)
				)
				(justify mirror)
			)
		)
		(property "Value" ""
			(at 0 0 0)
			(layer "B.Fab")
			(effects
				(font
					(size 1.27 1.27)
				)
				(justify mirror)
			)
		)
		(duplicate_pad_numbers_are_jumpers no)
		(fp_line
			(start -0.7874 -0.4064)
			(end -0.7874 0.4064)
			(stroke
				(width 0.1524)
				(type default)
			)
			(layer "B.SilkS")
		)
		(fp_line
			(start -0.7874 0.4064)
			(end 0.7874 0.4064)
			(stroke
				(width 0.1524)
				(type default)
			)
			(layer "B.SilkS")
		)
		(fp_line
			(start 0.7874 -0.4064)
			(end -0.7874 -0.4064)
			(stroke
				(width 0.1524)
				(type default)
			)
			(layer "B.SilkS")
		)
		(fp_line
			(start 0.7874 0.4064)
			(end 0.7874 -0.4064)
			(stroke
				(width 0.1524)
				(type default)
			)
			(layer "B.SilkS")
		)
		(fp_line
			(start -0.67945 -0.3048)
			(end -0.67945 0.3048)
			(stroke
				(width 0.1)
				(type default)
			)
			(layer "B.Fab")
		)
		(fp_line
			(start -0.67945 0.3048)
			(end -0.120396 0.3048)
			(stroke
				(width 0.1)
				(type default)
			)
			(layer "B.Fab")
		)
		(fp_line
			(start -0.12065 -0.3048)
			(end -0.67945 -0.3048)
			(stroke
				(width 0.1)
				(type default)
			)
			(layer "B.Fab")
		)
		(fp_line
			(start -0.12065 -0.2794)
			(end -0.12065 -0.3048)
			(stroke
				(width 0.1)
				(type default)
			)
			(layer "B.Fab")
		)
		(fp_line
			(start -0.120396 0.2794)
			(end 0.12065 0.2794)
			(stroke
				(width 0.1)
				(type default)
			)
			(layer "B.Fab")
		)
		(fp_line
			(start -0.120396 0.3048)
			(end -0.120396 0.2794)
			(stroke
				(width 0.1)
				(type default)
			)
			(layer "B.Fab")
		)
		(fp_line
			(start 0.12065 -0.305054)
			(end 0.12065 -0.2794)
			(stroke
				(width 0.1)
				(type default)
			)
			(layer "B.Fab")
		)
		(fp_line
			(start 0.12065 -0.2794)
			(end -0.12065 -0.2794)
			(stroke
				(width 0.1)
				(type default)
			)
			(layer "B.Fab")
		)
		(fp_line
			(start 0.12065 0.2794)
			(end 0.12065 0.3048)
			(stroke
				(width 0.1)
				(type default)
			)
			(layer "B.Fab")
		)
		(fp_line
			(start 0.12065 0.3048)
			(end 0.67945 0.3048)
			(stroke
				(width 0.1)
				(type default)
			)
			(layer "B.Fab")
		)
		(fp_line
			(start 0.67945 -0.305054)
			(end 0.12065 -0.305054)
			(stroke
				(width 0.1)
				(type default)
			)
			(layer "B.Fab")
		)
		(fp_line
			(start 0.67945 0.3048)
			(end 0.67945 -0.305054)
			(stroke
				(width 0.1)
				(type default)
			)
			(layer "B.Fab")
		)
		(pad "1" smd circle
			(at 0.40005 0 180)
			(size 0 0)
			(layers "B.Cu" "B.Mask" "B.Paste")
			(net "PVDDCR_SOC_P0")
		)
		(pad "2" smd circle
			(at -0.40005 0 180)
			(size 0 0)
			(layers "B.Cu" "B.Mask" "B.Paste")
			(net "GND")
		)
	)
)
